(kicad_pcb
	(version 20241229)
	(generator "pcbnew")
	(generator_version "9.0")
	(general
		(thickness 1.61)
		(legacy_teardrops no)
	)
	(paper "A3")
	(title_block
		(title "SO-DIMM DDR5 Tester")
		(date "2025-11-26")
		(rev "1.3.0")
		(comment 9 "footprints 461-466 of 627")
	)
	(layers
		(0 "F.Cu" signal)
		(4 "In1.Cu" power)
		(6 "In2.Cu" mixed)
		(8 "In3.Cu" power)
		(10 "In4.Cu" mixed)
		(12 "In5.Cu" power)
		(14 "In6.Cu" mixed)
		(16 "In7.Cu" power)
		(18 "In8.Cu" power)
		(20 "In9.Cu" mixed)
		(22 "In10.Cu" power)
		(2 "B.Cu" signal)
		(9 "F.Adhes" user "F.Adhesive")
		(11 "B.Adhes" user "B.Adhesive")
		(13 "F.Paste" user)
		(15 "B.Paste" user)
		(5 "F.SilkS" user "F.Silkscreen")
		(7 "B.SilkS" user "B.Silkscreen")
		(1 "F.Mask" user)
		(3 "B.Mask" user)
		(17 "Dwgs.User" user "User.Drawings")
		(19 "Cmts.User" user "User.Comments")
		(21 "Eco1.User" user "User.Eco1")
		(23 "Eco2.User" user "User.Eco2")
		(25 "Edge.Cuts" user)
		(27 "Margin" user)
		(31 "F.CrtYd" user "F.Courtyard")
		(29 "B.CrtYd" user "B.Courtyard")
		(35 "F.Fab" user)
		(33 "B.Fab" user)
	)
	(footprint "antmicro-footprints:C_0402_1005Metric"
		(layer "B.Cu")
		(at 136.877002 171.3025 180)
		(descr "Capacitor SMD 0402 (1005 Metric), square (rectangular) end terminal, IPC_7351 nominal, (Body size source: IPC-SM-782 page 76, https://www.pcb-3d.com/wordpress/wp-content/uploads/ipc-sm-782a_amendment_1_and_2.pdf)")
		(tags "capacitor 0402")
		(property "Reference" "C26"
			(at 0 1.17 0)
			(layer "B.SilkS")
			(hide yes)
			(effects
				(font
					(size 0.7 0.7)
					(thickness 0.15)
				)
				(justify left bottom mirror)
			)
		)
		(property "Value" "C_100n_0402"
			(at 0 -1.169 0)
			(layer "B.Fab")
			(effects
				(font
					(size 0.7 0.7)
					(thickness 0.15)
				)
				(justify left bottom mirror)
			)
		)
		(property "Datasheet" "https://www.murata.com/products/productdetail?partno=GRM155R61H104KE14%23"
			(at 0 0 180)
			(layer "F.Fab")
			(hide yes)
			(effects
				(font
					(size 1.27 1.27)
					(thickness 0.15)
				)
			)
		)
		(property "Author" "Antmicro"
			(at 273.754004 342.605 0)
			(layer "B.Fab")
			(hide yes)
			(effects
				(font
					(size 1 1)
					(thickness 0.15)
				)
				(justify mirror)
			)
		)
		(property "Dielectric" "X5R"
			(at 273.754004 342.605 0)
			(layer "B.Fab")
			(hide yes)
			(effects
				(font
					(size 1 1)
					(thickness 0.15)
				)
				(justify mirror)
			)
		)
		(property "License" "Apache-2.0"
			(at 273.754004 342.605 0)
			(layer "B.Fab")
			(hide yes)
			(effects
				(font
					(size 1 1)
					(thickness 0.15)
				)
				(justify mirror)
			)
		)
		(property "MPN" "GRM155R61H104KE14D"
			(at 273.754004 342.605 0)
			(layer "B.Fab")
			(hide yes)
			(effects
				(font
					(size 1 1)
					(thickness 0.15)
				)
				(justify mirror)
			)
		)
		(property "Manufacturer" "Murata"
			(at 273.754004 342.605 0)
			(layer "B.Fab")
			(hide yes)
			(effects
				(font
					(size 1 1)
					(thickness 0.15)
				)
				(justify mirror)
			)
		)
		(property "Val" "100n"
			(at 273.754004 342.605 0)
			(layer "B.Fab")
			(hide yes)
			(effects
				(font
					(size 1 1)
					(thickness 0.15)
				)
				(justify mirror)
			)
		)
		(property "Voltage" "50V"
			(at 273.754004 342.605 0)
			(layer "B.Fab")
			(hide yes)
			(effects
				(font
					(size 1 1)
					(thickness 0.15)
				)
				(justify mirror)
			)
		)
		(sheetname "/FPGA power/")
		(sheetfile "fpga-power.kicad_sch")
		(attr smd)
		(fp_rect
			(start -0.9656 0.4572)
			(end 0.9652 -0.4828)
			(stroke
				(width 0.05)
				(type solid)
			)
			(fill no)
			(layer "B.CrtYd")
		)
		(fp_line
			(start 0.498 0.25)
			(end 0.498 -0.248)
			(stroke
				(width 0.15)
				(type solid)
			)
			(layer "B.Fab")
		)
		(fp_line
			(start 0.498 -0.248)
			(end -0.5 -0.248)
			(stroke
				(width 0.15)
				(type solid)
			)
			(layer "B.Fab")
		)
		(fp_line
			(start -0.5 0.25)
			(end 0.498 0.25)
			(stroke
				(width 0.15)
				(type solid)
			)
			(layer "B.Fab")
		)
		(fp_line
			(start -0.5 -0.248)
			(end -0.5 0.25)
			(stroke
				(width 0.15)
				(type solid)
			)
			(layer "B.Fab")
		)
		(pad "1" smd roundrect
			(at -0.5 0 90)
			(size 0.6 0.6)
			(layers "B.Cu" "B.Mask" "B.Paste")
			(roundrect_rratio 0.25)
			(net 1 "GND")
			(pintype "passive")
		)
		(pad "2" smd roundrect
			(at 0.498 0 180)
			(size 0.6 0.6)
			(layers "B.Cu" "B.Mask" "B.Paste")
			(roundrect_rratio 0.25)
			(net 227 "+1V0")
			(pintype "passive")
		)
	)
	(footprint "antmicro-footprints:R_0402_1005Metric"
		(layer "B.Cu")
		(at 122.350501 175.426 180)
		(descr "Resistor SMD 0402")
		(tags "resistor SMD 0402")
		(property "Reference" "R2"
			(at -1.122484 0.772697 0)
			(layer "B.SilkS")
			(hide yes)
			(effects
				(font
					(size 0.7 0.7)
					(thickness 0.15)
				)
				(justify left bottom mirror)
			)
		)
		(property "Value" "R_10k_0402"
			(at -1.011843 -1.772047 0)
			(layer "B.Fab")
			(effects
				(font
					(size 0.7 0.7)
					(thickness 0.15)
				)
				(justify left bottom mirror)
			)
		)
		(property "Datasheet" "https://www.bourns.com/docs/product-datasheets/cr.pdf"
			(at 0 0 180)
			(layer "F.Fab")
			(hide yes)
			(effects
				(font
					(size 1.27 1.27)
					(thickness 0.15)
				)
			)
		)
		(property "Author" "Antmicro"
			(at 244.701002 350.852 0)
			(layer "B.Fab")
			(hide yes)
			(effects
				(font
					(size 1 1)
					(thickness 0.15)
				)
				(justify mirror)
			)
		)
		(property "License" "Apache-2.0"
			(at 244.701002 350.852 0)
			(layer "B.Fab")
			(hide yes)
			(effects
				(font
					(size 1 1)
					(thickness 0.15)
				)
				(justify mirror)
			)
		)
		(property "MPN" "CR0402-FX-1002GLF"
			(at 244.701002 350.852 0)
			(layer "B.Fab")
			(hide yes)
			(effects
				(font
					(size 1 1)
					(thickness 0.15)
				)
				(justify mirror)
			)
		)
		(property "Manufacturer" "Bourns"
			(at 244.701002 350.852 0)
			(layer "B.Fab")
			(hide yes)
			(effects
				(font
					(size 1 1)
					(thickness 0.15)
				)
				(justify mirror)
			)
		)
		(property "Tolerance" "1%"
			(at 244.701002 350.852 0)
			(layer "B.Fab")
			(hide yes)
			(effects
				(font
					(size 1 1)
					(thickness 0.15)
				)
				(justify mirror)
			)
		)
		(property "Val" "10k"
			(at 244.701002 350.852 0)
			(layer "B.Fab")
			(hide yes)
			(effects
				(font
					(size 1 1)
					(thickness 0.15)
				)
				(justify mirror)
			)
		)
		(sheetname "/HyperRAM + QSPI Flash/")
		(sheetfile "hyperram-flash.kicad_sch")
		(attr smd)
		(fp_rect
			(start -0.93 0.47)
			(end 0.93 -0.47)
			(stroke
				(width 0.05)
				(type solid)
			)
			(fill no)
			(layer "B.CrtYd")
		)
		(fp_rect
			(start -0.5 0.25)
			(end 0.5 -0.25)
			(stroke
				(width 0.15)
				(type solid)
			)
			(fill no)
			(layer "B.Fab")
		)
		(pad "1" smd roundrect
			(at -0.485 0 180)
			(size 0.59 0.64)
			(layers "B.Cu" "B.Mask" "B.Paste")
			(roundrect_rratio 0.25)
			(net 200 "+3V3")
			(pintype "passive")
		)
		(pad "2" smd roundrect
			(at 0.485 0 180)
			(size 0.59 0.64)
			(layers "B.Cu" "B.Mask" "B.Paste")
			(roundrect_rratio 0.25)
			(net 624 "/FPGA bank 12/HyperRAM.~{CS}")
			(pintype "passive")
		)
	)
	(footprint "antmicro-footprints:C_0402_1005Metric"
		(layer "B.Cu")
		(at 147.875001 179.3005 180)
		(descr "Capacitor SMD 0402 (1005 Metric), square (rectangular) end terminal, IPC_7351 nominal, (Body size source: IPC-SM-782 page 76, https://www.pcb-3d.com/wordpress/wp-content/uploads/ipc-sm-782a_amendment_1_and_2.pdf)")
		(tags "capacitor 0402")
		(property "Reference" "C99"
			(at 0 1.17 0)
			(layer "B.SilkS")
			(hide yes)
			(effects
				(font
					(size 0.7 0.7)
					(thickness 0.15)
				)
				(justify left bottom mirror)
			)
		)
		(property "Value" "C_100n_0402"
			(at 0 -1.169 0)
			(layer "B.Fab")
			(effects
				(font
					(size 0.7 0.7)
					(thickness 0.15)
				)
				(justify left bottom mirror)
			)
		)
		(property "Datasheet" "https://www.murata.com/products/productdetail?partno=GRM155R61H104KE14%23"
			(at 0 0 180)
			(layer "F.Fab")
			(hide yes)
			(effects
				(font
					(size 1.27 1.27)
					(thickness 0.15)
				)
			)
		)
		(property "Author" "Antmicro"
			(at 295.750002 358.601 0)
			(layer "B.Fab")
			(hide yes)
			(effects
				(font
					(size 1 1)
					(thickness 0.15)
				)
				(justify mirror)
			)
		)
		(property "Dielectric" "X5R"
			(at 295.750002 358.601 0)
			(layer "B.Fab")
			(hide yes)
			(effects
				(font
					(size 1 1)
					(thickness 0.15)
				)
				(justify mirror)
			)
		)
		(property "License" "Apache-2.0"
			(at 295.750002 358.601 0)
			(layer "B.Fab")
			(hide yes)
			(effects
				(font
					(size 1 1)
					(thickness 0.15)
				)
				(justify mirror)
			)
		)
		(property "MPN" "GRM155R61H104KE14D"
			(at 295.750002 358.601 0)
			(layer "B.Fab")
			(hide yes)
			(effects
				(font
					(size 1 1)
					(thickness 0.15)
				)
				(justify mirror)
			)
		)
		(property "Manufacturer" "Murata"
			(at 295.750002 358.601 0)
			(layer "B.Fab")
			(hide yes)
			(effects
				(font
					(size 1 1)
					(thickness 0.15)
				)
				(justify mirror)
			)
		)
		(property "Val" "100n"
			(at 295.750002 358.601 0)
			(layer "B.Fab")
			(hide yes)
			(effects
				(font
					(size 1 1)
					(thickness 0.15)
				)
				(justify mirror)
			)
		)
		(property "Voltage" "50V"
			(at 295.750002 358.601 0)
			(layer "B.Fab")
			(hide yes)
			(effects
				(font
					(size 1 1)
					(thickness 0.15)
				)
				(justify mirror)
			)
		)
		(sheetname "/FPGA power/")
		(sheetfile "fpga-power.kicad_sch")
		(attr smd)
		(fp_rect
			(start -0.9656 0.4572)
			(end 0.9652 -0.4828)
			(stroke
				(width 0.05)
				(type solid)
			)
			(fill no)
			(layer "B.CrtYd")
		)
		(fp_line
			(start 0.498 0.25)
			(end 0.498 -0.248)
			(stroke
				(width 0.15)
				(type solid)
			)
			(layer "B.Fab")
		)
		(fp_line
			(start 0.498 -0.248)
			(end -0.5 -0.248)
			(stroke
				(width 0.15)
				(type solid)
			)
			(layer "B.Fab")
		)
		(fp_line
			(start -0.5 0.25)
			(end 0.498 0.25)
			(stroke
				(width 0.15)
				(type solid)
			)
			(layer "B.Fab")
		)
		(fp_line
			(start -0.5 -0.248)
			(end -0.5 0.25)
			(stroke
				(width 0.15)
				(type solid)
			)
			(layer "B.Fab")
		)
		(pad "1" smd roundrect
			(at -0.5 0 90)
			(size 0.6 0.6)
			(layers "B.Cu" "B.Mask" "B.Paste")
			(roundrect_rratio 0.25)
			(net 1 "GND")
			(pintype "passive")
		)
		(pad "2" smd roundrect
			(at 0.498 0 180)
			(size 0.6 0.6)
			(layers "B.Cu" "B.Mask" "B.Paste")
			(roundrect_rratio 0.25)
			(net 187 "+1V0_MGTAVCC")
			(pintype "passive")
		)
	)
	(footprint "antmicro-footprints:C_0402_1005Metric"
		(layer "B.Cu")
		(at 127.875501 165.301 180)
		(descr "Capacitor SMD 0402 (1005 Metric), square (rectangular) end terminal, IPC_7351 nominal, (Body size source: IPC-SM-782 page 76, https://www.pcb-3d.com/wordpress/wp-content/uploads/ipc-sm-782a_amendment_1_and_2.pdf)")
		(tags "capacitor 0402")
		(property "Reference" "C35"
			(at 0 1.17 0)
			(layer "B.SilkS")
			(hide yes)
			(effects
				(font
					(size 0.7 0.7)
					(thickness 0.15)
				)
				(justify left bottom mirror)
			)
		)
		(property "Value" "C_100n_0402"
			(at 0 -1.169 0)
			(layer "B.Fab")
			(effects
				(font
					(size 0.7 0.7)
					(thickness 0.15)
				)
				(justify left bottom mirror)
			)
		)
		(property "Datasheet" "https://www.murata.com/products/productdetail?partno=GRM155R61H104KE14%23"
			(at 0 0 180)
			(layer "F.Fab")
			(hide yes)
			(effects
				(font
					(size 1.27 1.27)
					(thickness 0.15)
				)
			)
		)
		(property "Author" "Antmicro"
			(at 255.751002 330.602 0)
			(layer "B.Fab")
			(hide yes)
			(effects
				(font
					(size 1 1)
					(thickness 0.15)
				)
				(justify mirror)
			)
		)
		(property "Dielectric" "X5R"
			(at 255.751002 330.602 0)
			(layer "B.Fab")
			(hide yes)
			(effects
				(font
					(size 1 1)
					(thickness 0.15)
				)
				(justify mirror)
			)
		)
		(property "License" "Apache-2.0"
			(at 255.751002 330.602 0)
			(layer "B.Fab")
			(hide yes)
			(effects
				(font
					(size 1 1)
					(thickness 0.15)
				)
				(justify mirror)
			)
		)
		(property "MPN" "GRM155R61H104KE14D"
			(at 255.751002 330.602 0)
			(layer "B.Fab")
			(hide yes)
			(effects
				(font
					(size 1 1)
					(thickness 0.15)
				)
				(justify mirror)
			)
		)
		(property "Manufacturer" "Murata"
			(at 255.751002 330.602 0)
			(layer "B.Fab")
			(hide yes)
			(effects
				(font
					(size 1 1)
					(thickness 0.15)
				)
				(justify mirror)
			)
		)
		(property "Val" "100n"
			(at 255.751002 330.602 0)
			(layer "B.Fab")
			(hide yes)
			(effects
				(font
					(size 1 1)
					(thickness 0.15)
				)
				(justify mirror)
			)
		)
		(property "Voltage" "50V"
			(at 255.751002 330.602 0)
			(layer "B.Fab")
			(hide yes)
			(effects
				(font
					(size 1 1)
					(thickness 0.15)
				)
				(justify mirror)
			)
		)
		(sheetname "/FPGA power/")
		(sheetfile "fpga-power.kicad_sch")
		(attr smd)
		(fp_rect
			(start -0.9656 0.4572)
			(end 0.9652 -0.4828)
			(stroke
				(width 0.05)
				(type solid)
			)
			(fill no)
			(layer "B.CrtYd")
		)
		(fp_line
			(start 0.498 0.25)
			(end 0.498 -0.248)
			(stroke
				(width 0.15)
				(type solid)
			)
			(layer "B.Fab")
		)
		(fp_line
			(start 0.498 -0.248)
			(end -0.5 -0.248)
			(stroke
				(width 0.15)
				(type solid)
			)
			(layer "B.Fab")
		)
		(fp_line
			(start -0.5 0.25)
			(end 0.498 0.25)
			(stroke
				(width 0.15)
				(type solid)
			)
			(layer "B.Fab")
		)
		(fp_line
			(start -0.5 -0.248)
			(end -0.5 0.25)
			(stroke
				(width 0.15)
				(type solid)
			)
			(layer "B.Fab")
		)
		(pad "1" smd roundrect
			(at -0.5 0 90)
			(size 0.6 0.6)
			(layers "B.Cu" "B.Mask" "B.Paste")
			(roundrect_rratio 0.25)
			(net 1 "GND")
			(pintype "passive")
		)
		(pad "2" smd roundrect
			(at 0.498 0 180)
			(size 0.6 0.6)
			(layers "B.Cu" "B.Mask" "B.Paste")
			(roundrect_rratio 0.25)
			(net 200 "+3V3")
			(pintype "passive")
		)
	)
	(footprint "antmicro-footprints:TP_SMD_1mm"
		(layer "B.Cu")
		(at 200.6 154.3 90)
		(property "Reference" "TP38"
			(at -3.4 -0.2 90)
			(layer "B.SilkS")
			(effects
				(font
					(size 0.7 0.7)
					(thickness 0.15)
				)
				(justify right top mirror)
			)
		)
		(property "Value" "TP_1mm_SMD"
			(at 0 -1.4 90)
			(layer "B.Fab")
			(effects
				(font
					(size 0.7 0.7)
					(thickness 0.15)
				)
				(justify right top mirror)
			)
		)
		(property "MPN" ""
			(at 0 0 270)
			(unlocked yes)
			(layer "B.Fab")
			(hide yes)
			(effects
				(font
					(size 1 1)
					(thickness 0.15)
				)
				(justify mirror)
			)
		)
		(property "Manufacturer" ""
			(at 0 0 270)
			(unlocked yes)
			(layer "B.Fab")
			(hide yes)
			(effects
				(font
					(size 1 1)
					(thickness 0.15)
				)
				(justify mirror)
			)
		)
		(property "Author" "Antmicro"
			(at 0 0 270)
			(unlocked yes)
			(layer "B.Fab")
			(hide yes)
			(effects
				(font
					(size 1 1)
					(thickness 0.15)
				)
				(justify mirror)
			)
		)
		(property "License" "Apache-2.0"
			(at 0 0 270)
			(unlocked yes)
			(layer "B.Fab")
			(hide yes)
			(effects
				(font
					(size 1 1)
					(thickness 0.15)
				)
				(justify mirror)
			)
		)
		(sheetname "/I^{2}C/")
		(sheetfile "i2c.kicad_sch")
		(attr exclude_from_pos_files)
		(fp_circle
			(center 0 0)
			(end 0.6 0)
			(stroke
				(width 0.05)
				(type default)
			)
			(fill no)
			(layer "B.CrtYd")
		)
		(fp_text user "Author: Antmicro"
			(at -0.5 -4 90)
			(layer "B.Fab")
			(effects
				(font
					(size 0.7 0.7)
					(thickness 0.15)
				)
				(justify right top mirror)
			)
		)
		(fp_text user "License: Apache-2.0"
			(at -0.5 -5.2 90)
			(layer "B.Fab")
			(effects
				(font
					(size 0.7 0.7)
					(thickness 0.15)
				)
				(justify right top mirror)
			)
		)
		(fp_text user "${REFERENCE}"
			(at -0.5 -2.8 90)
			(layer "B.Fab")
			(effects
				(font
					(size 0.7 0.7)
					(thickness 0.15)
				)
				(justify right top mirror)
			)
		)
		(pad "1" smd circle
			(at 0 0 90)
			(size 1 1)
			(layers "B.Cu" "B.Mask")
			(net 690 "/I^{2}C/PWR.SDA")
			(pinfunction "1")
			(pintype "passive")
		)
	)
	(footprint "antmicro-footprints:TP_SMD_1mm"
		(layer "B.Cu")
		(at 110 174.13 180)
		(property "Reference" "TP51"
			(at -3.2 -0.47 0)
			(layer "B.SilkS")
			(effects
				(font
					(size 0.7 0.7)
					(thickness 0.15)
				)
				(justify left bottom mirror)
			)
		)
		(property "Value" "TP_1mm_SMD"
			(at 0 -1.4 0)
			(layer "B.Fab")
			(effects
				(font
					(size 0.7 0.7)
					(thickness 0.15)
				)
				(justify left bottom mirror)
			)
		)
		(property "MPN" ""
			(at 0 0 0)
			(unlocked yes)
			(layer "B.Fab")
			(hide yes)
			(effects
				(font
					(size 1 1)
					(thickness 0.15)
				)
				(justify mirror)
			)
		)
		(property "Manufacturer" ""
			(at 0 0 0)
			(unlocked yes)
			(layer "B.Fab")
			(hide yes)
			(effects
				(font
					(size 1 1)
					(thickness 0.15)
				)
				(justify mirror)
			)
		)
		(property "Author" "Antmicro"
			(at 0 0 0)
			(unlocked yes)
			(layer "B.Fab")
			(hide yes)
			(effects
				(font
					(size 1 1)
					(thickness 0.15)
				)
				(justify mirror)
			)
		)
		(property "License" "Apache-2.0"
			(at 0 0 0)
			(unlocked yes)
			(layer "B.Fab")
			(hide yes)
			(effects
				(font
					(size 1 1)
					(thickness 0.15)
				)
				(justify mirror)
			)
		)
		(sheetname "/Debug FTDI/")
		(sheetfile "debug-ftdi.kicad_sch")
		(attr exclude_from_pos_files)
		(fp_circle
			(center 0 0)
			(end 0.6 0)
			(stroke
				(width 0.05)
				(type default)
			)
			(fill no)
			(layer "B.CrtYd")
		)
		(fp_text user "Author: Antmicro"
			(at -0.5 -4 0)
			(layer "B.Fab")
			(effects
				(font
					(size 0.7 0.7)
					(thickness 0.15)
				)
				(justify left bottom mirror)
			)
		)
		(fp_text user "License: Apache-2.0"
			(at -0.5 -5.2 0)
			(layer "B.Fab")
			(effects
				(font
					(size 0.7 0.7)
					(thickness 0.15)
				)
				(justify left bottom mirror)
			)
		)
		(fp_text user "${REFERENCE}"
			(at -0.5 -2.8 0)
			(layer "B.Fab")
			(effects
				(font
					(size 0.7 0.7)
					(thickness 0.15)
				)
				(justify left bottom mirror)
			)
		)
		(pad "1" smd circle
			(at 0 0 180)
			(size 1 1)
			(layers "B.Cu" "B.Mask")
			(net 643 "/Debug FTDI/UART1.RX")
			(pinfunction "1")
			(pintype "passive")
		)
	)
)
